# BASEBOARD_FAB2 (Tioga Pass) — schematic netlist excerpt (pin names and nets, part order shuffled) for the footprints in the layout excerpt that follows; sources: Cadence DE-HDL packaged netlist, KiCad conversion of Wiwynn_Tioga_Pass_MB.brd

C3D2  CAP_A  22.0UF 4V 20% X6S  pkg 0603V  page 76 : A = PVCCIN_CPU1 ; B = GND
R8A2  RES  2.67K 1% CHIP  pkg 0402  page 235 : A = VR_PVNN_PCH_XADDR2 ; B = GND
C3D20  CAP_A  22.0UF 4V 20% X6S  pkg 0603V  page 76 : A = PVCCMCP_CPU1 ; B = GND

(kicad_pcb
	(version 20260206)
	(generator "pcbnew")
	(generator_version "10.0")
	(general
		(thickness 1.6)
		(legacy_teardrops no)
	)
	(paper "A4")
	(title_block
		(title "Wiwynn_Tioga_Pass_MB.brd")
		(comment 1 "Tioga Pass / footprints 2219-2221 of 4770")
	)
	(layers
		(0 "F.Cu" signal "TOP")
		(4 "In1.Cu" signal "L2GND")
		(6 "In2.Cu" signal "L3")
		(8 "In3.Cu" signal "L4GND")
		(10 "In4.Cu" signal "L5")
		(12 "In5.Cu" signal "L6GND")
		(14 "In6.Cu" signal "L7VCC")
		(16 "In7.Cu" signal "L8VCC")
		(18 "In8.Cu" signal "L9GND")
		(20 "In9.Cu" signal "L10")
		(22 "In10.Cu" signal "L11GND")
		(24 "In11.Cu" signal "L12")
		(26 "In12.Cu" signal "L13GND")
		(2 "B.Cu" signal "BOTTOM")
		(9 "F.Adhes" user "F.Adhesive")
		(11 "B.Adhes" user "B.Adhesive")
		(13 "F.Paste" user "Package Geometry/Pastemask Top")
		(15 "B.Paste" user "Package Geometry/Pastemask Bottom")
		(5 "F.SilkS" user "Ref Des/Silkscreen Top")
		(7 "B.SilkS" user "Ref Des/Silkscreen Bottom")
		(1 "F.Mask" user "Board Geometry/Soldermask Top")
		(3 "B.Mask" user "Board Geometry/Soldermask Bottom")
		(17 "Dwgs.User" user "User.Drawings")
		(19 "Cmts.User" user "User.Comments")
		(21 "Eco1.User" user "User.Eco1")
		(23 "Eco2.User" user "User.Eco2")
		(25 "Edge.Cuts" user "Board Geometry/Outline")
		(27 "Margin" user)
		(31 "F.CrtYd" user "Package Geometry/Place Bound Top")
		(29 "B.CrtYd" user "Package Geometry/Place Bound Bottom")
		(35 "F.Fab" user "Ref Des/Assembly Top")
		(33 "B.Fab" user "Ref Des/Assembly Bottom")
	)
	(footprint ""
		(layer "F.Cu")
		(at 108.48721 -84.890102)
		(property "Reference" "C3D2"
			(at 0 0 0)
			(layer "F.SilkS")
			(hide yes)
			(effects
				(font
					(size 1.27 1.27)
				)
			)
		)
		(property "Value" ""
			(at 0 0 0)
			(layer "F.Fab")
			(effects
				(font
					(size 1.27 1.27)
				)
			)
		)
		(duplicate_pad_numbers_are_jumpers no)
		(fp_poly
			(pts
				(xy -0.4953 -0.2032) (xy 0.4953 -0.2032) (xy 0.4953 1.6002) (xy -0.4953 1.6002)
			)
			(stroke
				(width 0)
				(type default)
			)
			(fill no)
			(layer "F.CrtYd")
		)
		(fp_line
			(start -0.4953 -0.2032)
			(end 0.4953 -0.2032)
			(stroke
				(width 0.1)
				(type default)
			)
			(layer "F.Fab")
		)
		(fp_line
			(start -0.4953 1.6002)
			(end -0.4953 -0.2032)
			(stroke
				(width 0.1)
				(type default)
			)
			(layer "F.Fab")
		)
		(fp_line
			(start 0.4953 -0.2032)
			(end 0.4953 1.6002)
			(stroke
				(width 0.1)
				(type default)
			)
			(layer "F.Fab")
		)
		(fp_line
			(start 0.4953 1.6002)
			(end -0.4953 1.6002)
			(stroke
				(width 0.1)
				(type default)
			)
			(layer "F.Fab")
		)
		(pad "1" smd rect
			(at 0 0)
			(size 0.762 0.889)
			(layers "F.Cu" "F.Mask" "F.Paste")
			(net "PVCCIN_CPU1")
		)
		(pad "2" smd rect
			(at 0 1.397)
			(size 0.762 0.889)
			(layers "F.Cu" "F.Mask" "F.Paste")
			(net "GND")
		)
		(zone
			(layer "F.Cu")
			(hatch none 0.5)
			(connect_pads
				(clearance 0)
			)
			(min_thickness 0.25)
			(keepout
				(tracks not_allowed)
				(vias allowed)
				(pads allowed)
				(copperpour not_allowed)
				(footprints allowed)
			)
			(placement
				(enabled no)
				(sheetname "")
			)
			(fill
				(thermal_gap 0.5)
				(thermal_bridge_width 0.5)
				(island_removal_mode 0)
			)
			(polygon
				(pts
					(xy 108.10621 -84.445602) (xy 108.86821 -84.445602) (xy 108.86821 -83.937602) (xy 108.10621 -83.937602)
				)
			)
		)
	)
	(footprint ""
		(layer "F.Cu")
		(at 111.97844 -73.318116)
		(property "Reference" "C3D20"
			(at 0 0 0)
			(layer "F.SilkS")
			(hide yes)
			(effects
				(font
					(size 1.27 1.27)
				)
			)
		)
		(property "Value" ""
			(at 0 0 0)
			(layer "F.Fab")
			(effects
				(font
					(size 1.27 1.27)
				)
			)
		)
		(duplicate_pad_numbers_are_jumpers no)
		(fp_poly
			(pts
				(xy -0.4953 -0.2032) (xy 0.4953 -0.2032) (xy 0.4953 1.6002) (xy -0.4953 1.6002)
			)
			(stroke
				(width 0)
				(type default)
			)
			(fill no)
			(layer "F.CrtYd")
		)
		(fp_line
			(start -0.4953 -0.2032)
			(end 0.4953 -0.2032)
			(stroke
				(width 0.1)
				(type default)
			)
			(layer "F.Fab")
		)
		(fp_line
			(start -0.4953 1.6002)
			(end -0.4953 -0.2032)
			(stroke
				(width 0.1)
				(type default)
			)
			(layer "F.Fab")
		)
		(fp_line
			(start 0.4953 -0.2032)
			(end 0.4953 1.6002)
			(stroke
				(width 0.1)
				(type default)
			)
			(layer "F.Fab")
		)
		(fp_line
			(start 0.4953 1.6002)
			(end -0.4953 1.6002)
			(stroke
				(width 0.1)
				(type default)
			)
			(layer "F.Fab")
		)
		(pad "1" smd rect
			(at 0 0)
			(size 0.762 0.889)
			(layers "F.Cu" "F.Mask" "F.Paste")
			(net "PVCCMCP_CPU1")
		)
		(pad "2" smd rect
			(at 0 1.397)
			(size 0.762 0.889)
			(layers "F.Cu" "F.Mask" "F.Paste")
			(net "GND")
		)
		(zone
			(layer "F.Cu")
			(hatch none 0.5)
			(connect_pads
				(clearance 0)
			)
			(min_thickness 0.25)
			(keepout
				(tracks not_allowed)
				(vias allowed)
				(pads allowed)
				(copperpour not_allowed)
				(footprints allowed)
			)
			(placement
				(enabled no)
				(sheetname "")
			)
			(fill
				(thermal_gap 0.5)
				(thermal_bridge_width 0.5)
				(island_removal_mode 0)
			)
			(polygon
				(pts
					(xy 111.59744 -72.873616) (xy 112.35944 -72.873616) (xy 112.35944 -72.365616) (xy 111.59744 -72.365616)
				)
			)
		)
	)
	(footprint ""
		(layer "F.Cu")
		(at 391.795 -155.067 -90)
		(property "Reference" "R8A2"
			(at 0 0 270)
			(layer "F.SilkS")
			(hide yes)
			(effects
				(font
					(size 1.27 1.27)
				)
			)
		)
		(property "Value" ""
			(at 0 0 270)
			(layer "F.Fab")
			(effects
				(font
					(size 1.27 1.27)
				)
			)
		)
		(duplicate_pad_numbers_are_jumpers no)
		(fp_poly
			(pts
				(xy -0.2794 -0.1016) (xy 0.2794 -0.1016) (xy 0.2794 0.9906) (xy -0.2794 0.9906)
			)
			(stroke
				(width 0)
				(type default)
			)
			(fill no)
			(layer "F.CrtYd")
		)
		(fp_line
			(start -0.2794 0.9906)
			(end 0.2794 0.9906)
			(stroke
				(width 0.1)
				(type default)
			)
			(layer "F.Fab")
		)
		(fp_line
			(start 0.2794 0.9906)
			(end 0.2794 -0.1016)
			(stroke
				(width 0.1)
				(type default)
			)
			(layer "F.Fab")
		)
		(fp_line
			(start -0.2794 -0.1016)
			(end -0.2794 0.9906)
			(stroke
				(width 0.1)
				(type default)
			)
			(layer "F.Fab")
		)
		(fp_line
			(start 0.2794 -0.1016)
			(end -0.2794 -0.1016)
			(stroke
				(width 0.1)
				(type default)
			)
			(layer "F.Fab")
		)
		(pad "1" smd rect
			(at 0 0 270)
			(size 0.508 0.508)
			(layers "F.Cu" "F.Mask" "F.Paste")
			(net "VR_PVNN_PCH_XADDR2")
		)
		(pad "2" smd rect
			(at 0 0.889 270)
			(size 0.508 0.508)
			(layers "F.Cu" "F.Mask" "F.Paste")
			(net "GND")
		)
		(zone
			(layer "F.Cu")
			(hatch none 0.5)
			(connect_pads
				(clearance 0)
			)
			(min_thickness 0.25)
			(keepout
				(tracks not_allowed)
				(vias allowed)
				(pads allowed)
				(copperpour not_allowed)
				(footprints allowed)
			)
			(placement
				(enabled no)
				(sheetname "")
			)
			(fill
				(thermal_gap 0.5)
				(thermal_bridge_width 0.5)
				(island_removal_mode 0)
			)
			(polygon
				(pts
					(xy 391.16 -155.321) (xy 391.16 -154.813) (xy 391.541 -154.813) (xy 391.541 -155.321)
				)
			)
		)
		(zone
			(layer "F.Cu")
			(hatch none 0.5)
			(connect_pads
				(clearance 0)
			)
			(min_thickness 0.25)
			(keepout
				(tracks allowed)
				(vias not_allowed)
				(pads allowed)
				(copperpour not_allowed)
				(footprints allowed)
			)
			(placement
				(enabled no)
				(sheetname "")
			)
			(fill
				(thermal_gap 0.5)
				(thermal_bridge_width 0.5)
				(island_removal_mode 0)
			)
			(polygon
				(pts
					(xy 391.541 -155.321) (xy 391.541 -154.813) (xy 391.16 -154.813) (xy 391.16 -155.321)
				)
			)
		)
	)
)
